(kicad_pcb
	(version 20260206)
	(generator "pcbnew")
	(generator_version "10.0")
	(general
		(thickness 1.6)
		(legacy_teardrops no)
	)
	(paper "A4")
	(title_block
		(title "Bryce Canyon_IOM_IOC_16318-2_OCP.brd")
		(comment 1 "Bryce Canyon / footprints 1444-1452 of 1605")
	)
	(layers
		(0 "F.Cu" signal "TOP")
		(4 "In1.Cu" signal "L2GND")
		(6 "In2.Cu" signal "L3")
		(8 "In3.Cu" signal "L4VCC")
		(10 "In4.Cu" signal "L5VCC")
		(12 "In5.Cu" signal "L6")
		(14 "In6.Cu" signal "L7GND")
		(2 "B.Cu" signal "BOTTOM")
		(9 "F.Adhes" user "F.Adhesive")
		(11 "B.Adhes" user "B.Adhesive")
		(13 "F.Paste" user "Package Geometry/Pastemask Top")
		(15 "B.Paste" user "Package Geometry/Pastemask Bottom")
		(5 "F.SilkS" user "Ref Des/Silkscreen Top")
		(7 "B.SilkS" user "Ref Des/Silkscreen Bottom")
		(1 "F.Mask" user "Board Geometry/Soldermask Top")
		(3 "B.Mask" user "Board Geometry/Soldermask Bottom")
		(17 "Dwgs.User" user "User.Drawings")
		(19 "Cmts.User" user "User.Comments")
		(21 "Eco1.User" user "User.Eco1")
		(23 "Eco2.User" user "User.Eco2")
		(25 "Edge.Cuts" user "Board Geometry/Outline")
		(27 "Margin" user)
		(31 "F.CrtYd" user "Package Geometry/Place Bound Top")
		(29 "B.CrtYd" user "Package Geometry/Place Bound Bottom")
		(35 "F.Fab" user "Ref Des/Assembly Top")
		(33 "B.Fab" user "Ref Des/Assembly Bottom")
	)
	(footprint ""
		(layer "B.Cu")
		(at 195.60286 -56.66232)
		(property "Reference" "C386"
			(at 0 0 0)
			(layer "B.SilkS")
			(hide yes)
			(effects
				(font
					(size 1.27 1.27)
				)
				(justify mirror)
			)
		)
		(property "Value" "SC10U6D3V5KX-4GP"
			(at 0.0762 -6.1214 0)
			(unlocked yes)
			(layer "B.Fab")
			(hide yes)
			(effects
				(font
					(size 1.016 1.016)
					(thickness 0.1524)
				)
				(justify mirror)
			)
		)
		(property "Device Type" "C805H58"
			(at 0.0762 -8.1534 0)
			(unlocked yes)
			(layer "B.Fab")
			(hide yes)
			(effects
				(font
					(size 1.016 1.016)
					(thickness 0.1524)
				)
				(justify mirror)
			)
		)
		(duplicate_pad_numbers_are_jumpers no)
		(fp_line
			(start -0.635 0)
			(end 0.635 0)
			(stroke
				(width 0.508)
				(type default)
			)
			(layer "B.SilkS")
		)
		(fp_rect
			(start 0.9652 1.778)
			(end -0.9652 -1.778)
			(stroke
				(width 0)
				(type default)
			)
			(fill no)
			(layer "B.CrtYd")
		)
		(fp_poly
			(pts
				(xy 0.9652 -1.778) (xy -0.9652 -1.778) (xy -0.9652 1.778) (xy 0.9652 1.778)
			)
			(stroke
				(width 0)
				(type default)
			)
			(fill no)
			(layer "B.Fab")
		)
		(pad "1" smd rect
			(at 0 -0.9652 180)
			(size 1.397 1.143)
			(layers "B.Cu" "B.Mask" "B.Paste")
			(net "P0V975")
		)
		(pad "2" smd rect
			(at 0 0.9652 180)
			(size 1.397 1.143)
			(layers "B.Cu" "B.Mask" "B.Paste")
			(net "GND")
		)
	)
	(footprint ""
		(layer "B.Cu")
		(at 200.279 -71.247 -90)
		(property "Reference" "C355"
			(at 0 0 90)
			(layer "B.SilkS")
			(hide yes)
			(effects
				(font
					(size 1.27 1.27)
				)
				(justify mirror)
			)
		)
		(property "Value" "SCD1U6D3V1KX-GP"
			(at 2.8321 -1.7399 270)
			(unlocked yes)
			(layer "B.Fab")
			(hide yes)
			(effects
				(font
					(size 1.016 1.016)
					(thickness 0.1524)
				)
				(justify mirror)
			)
		)
		(property "Device Type" "C0201H13"
			(at 2.8321 -3.2639 270)
			(unlocked yes)
			(layer "B.Fab")
			(hide yes)
			(effects
				(font
					(size 1.016 1.016)
					(thickness 0.1524)
				)
				(justify mirror)
			)
		)
		(duplicate_pad_numbers_are_jumpers no)
		(fp_rect
			(start 0.2794 0.6477)
			(end -0.2794 -0.6477)
			(stroke
				(width 0)
				(type default)
			)
			(fill no)
			(layer "B.CrtYd")
		)
		(fp_rect
			(start 0.2794 0.6477)
			(end -0.2794 -0.6477)
			(stroke
				(width 0)
				(type default)
			)
			(fill no)
			(layer "B.Fab")
		)
		(pad "1" smd custom
			(at 0 -0.2794 90)
			(size 0.0762 0.0762)
			(layers "B.Cu" "B.Mask" "B.Paste")
			(net "SAS0_VDDH")
			(options
				(clearance outline)
				(anchor circle)
			)
			(primitives
				(gr_poly
					(pts
						(arc
							(start 0.1524 0.127)
							(mid 0.137521 0.162921)
							(end 0.1016 0.1778)
						)
						(arc
							(start -0.1016 0.1778)
							(mid -0.137521 0.162921)
							(end -0.1524 0.127)
						)
						(arc
							(start -0.1524 -0.127)
							(mid -0.137521 -0.162921)
							(end -0.1016 -0.1778)
						)
						(arc
							(start 0.1016 -0.1778)
							(mid 0.137521 -0.162921)
							(end 0.1524 -0.127)
						)
					)
					(width 0)
					(fill yes)
				)
			)
		)
		(pad "2" smd custom
			(at 0 0.2794 90)
			(size 0.0762 0.0762)
			(layers "B.Cu" "B.Mask" "B.Paste")
			(net "GND")
			(options
				(clearance outline)
				(anchor circle)
			)
			(primitives
				(gr_poly
					(pts
						(arc
							(start 0.1524 0.127)
							(mid 0.137521 0.162921)
							(end 0.1016 0.1778)
						)
						(arc
							(start -0.1016 0.1778)
							(mid -0.137521 0.162921)
							(end -0.1524 0.127)
						)
						(arc
							(start -0.1524 -0.127)
							(mid -0.137521 -0.162921)
							(end -0.1016 -0.1778)
						)
						(arc
							(start 0.1016 -0.1778)
							(mid 0.137521 -0.162921)
							(end 0.1524 -0.127)
						)
					)
					(width 0)
					(fill yes)
				)
			)
		)
	)
	(footprint ""
		(layer "B.Cu")
		(at 17.749012 -129.051558 180)
		(property "Reference" "R240"
			(at 0 0 0)
			(layer "B.SilkS")
			(hide yes)
			(effects
				(font
					(size 1.27 1.27)
				)
				(justify mirror)
			)
		)
		(property "Value" "120R2F-GP"
			(at -0.064008 -3.993896 180)
			(unlocked yes)
			(layer "B.Fab")
			(hide yes)
			(effects
				(font
					(size 1.016 1.016)
					(thickness 0.1524)
				)
				(justify mirror)
			)
		)
		(property "Device Type" "R402H16"
			(at -0.064008 -5.517896 180)
			(unlocked yes)
			(layer "B.Fab")
			(hide yes)
			(effects
				(font
					(size 1.016 1.016)
					(thickness 0.1524)
				)
				(justify mirror)
			)
		)
		(duplicate_pad_numbers_are_jumpers no)
		(fp_line
			(start 0.508 -0.9398)
			(end 0.508 0.9398)
			(stroke
				(width 0.1524)
				(type default)
			)
			(layer "B.SilkS")
		)
		(fp_line
			(start -0.508 -0.9398)
			(end 0.508 -0.9398)
			(stroke
				(width 0.1524)
				(type default)
			)
			(layer "B.SilkS")
		)
		(fp_rect
			(start 0.508 0.9398)
			(end -0.508 -0.9398)
			(stroke
				(width 0)
				(type default)
			)
			(fill no)
			(layer "B.CrtYd")
		)
		(fp_rect
			(start 0.508 0.9398)
			(end -0.508 -0.9398)
			(stroke
				(width 0)
				(type default)
			)
			(fill no)
			(layer "B.Fab")
		)
		(pad "1" smd custom
			(at 0 -0.4445)
			(size 0.1397 0.1397)
			(layers "B.Cu" "B.Mask" "B.Paste")
			(net "GND")
			(options
				(clearance outline)
				(anchor circle)
			)
			(primitives
				(gr_poly
					(pts
						(arc
							(start -0.1778 0.2794)
							(mid -0.249642 0.249642)
							(end -0.2794 0.1778)
						)
						(arc
							(start -0.2794 -0.1778)
							(mid -0.249642 -0.249642)
							(end -0.1778 -0.2794)
						)
						(arc
							(start 0.1778 -0.2794)
							(mid 0.249642 -0.249642)
							(end 0.2794 -0.1778)
						)
						(arc
							(start 0.2794 0.1778)
							(mid 0.249642 0.249642)
							(end 0.1778 0.2794)
						)
					)
					(width 0)
					(fill yes)
				)
			)
		)
		(pad "2" smd custom
			(at 0 0.4445)
			(size 0.1397 0.1397)
			(layers "B.Cu" "B.Mask" "B.Paste")
			(net "MEMA_3")
			(options
				(clearance outline)
				(anchor circle)
			)
			(primitives
				(gr_poly
					(pts
						(arc
							(start -0.1778 0.2794)
							(mid -0.249642 0.249642)
							(end -0.2794 0.1778)
						)
						(arc
							(start -0.2794 -0.1778)
							(mid -0.249642 -0.249642)
							(end -0.1778 -0.2794)
						)
						(arc
							(start 0.1778 -0.2794)
							(mid 0.249642 -0.249642)
							(end 0.2794 -0.1778)
						)
						(arc
							(start 0.2794 0.1778)
							(mid 0.249642 0.249642)
							(end 0.1778 0.2794)
						)
					)
					(width 0)
					(fill yes)
				)
			)
		)
	)
	(footprint ""
		(layer "B.Cu")
		(at 186.358784 -76.451714)
		(property "Reference" "TP86"
			(at 0 0 0)
			(layer "B.SilkS")
			(hide yes)
			(effects
				(font
					(size 1.27 1.27)
				)
				(justify mirror)
			)
		)
		(property "Value" "TPAD28-2-GP"
			(at 0.0127 -1.6637 0)
			(unlocked yes)
			(layer "B.Fab")
			(hide yes)
			(effects
				(font
					(size 1.016 1.016)
					(thickness 0.1524)
				)
				(justify mirror)
			)
		)
		(property "Device Type" "TPAD28"
			(at 0.0127 -3.1877 0)
			(unlocked yes)
			(layer "B.Fab")
			(hide yes)
			(effects
				(font
					(size 1.016 1.016)
					(thickness 0.1524)
				)
				(justify mirror)
			)
		)
		(duplicate_pad_numbers_are_jumpers no)
		(fp_poly
			(pts
				(arc
					(start 0.3556 0)
					(mid -0.3556 0)
					(end 0.3556 0)
				)
			)
			(stroke
				(width 0)
				(type default)
			)
			(fill no)
			(layer "B.CrtYd")
		)
		(fp_poly
			(pts
				(arc
					(start 0.6096 0)
					(mid -0.6096 0)
					(end 0.6096 0)
				)
			)
			(stroke
				(width 0)
				(type default)
			)
			(fill no)
			(layer "B.Fab")
		)
		(pad "1" smd circle
			(at 0 0 180)
			(size 0.7112 0.7112)
			(layers "B.Cu" "B.Mask" "B.Paste")
			(net "IOC_GPIO_5")
		)
	)
	(footprint ""
		(layer "B.Cu")
		(at 16.294354 -131.007358 180)
		(property "Reference" "R259"
			(at 0 0 0)
			(layer "B.SilkS")
			(hide yes)
			(effects
				(font
					(size 1.27 1.27)
				)
				(justify mirror)
			)
		)
		(property "Value" "120R2F-GP"
			(at -0.064008 -3.993896 180)
			(unlocked yes)
			(layer "B.Fab")
			(hide yes)
			(effects
				(font
					(size 1.016 1.016)
					(thickness 0.1524)
				)
				(justify mirror)
			)
		)
		(property "Device Type" "R402H16"
			(at -0.064008 -5.517896 180)
			(unlocked yes)
			(layer "B.Fab")
			(hide yes)
			(effects
				(font
					(size 1.016 1.016)
					(thickness 0.1524)
				)
				(justify mirror)
			)
		)
		(duplicate_pad_numbers_are_jumpers no)
		(fp_line
			(start 0.508 -0.9398)
			(end 0.508 0.9398)
			(stroke
				(width 0.1524)
				(type default)
			)
			(layer "B.SilkS")
		)
		(fp_line
			(start -0.508 -0.9398)
			(end 0.508 -0.9398)
			(stroke
				(width 0.1524)
				(type default)
			)
			(layer "B.SilkS")
		)
		(fp_rect
			(start 0.508 0.9398)
			(end -0.508 -0.9398)
			(stroke
				(width 0)
				(type default)
			)
			(fill no)
			(layer "B.CrtYd")
		)
		(fp_rect
			(start 0.508 0.9398)
			(end -0.508 -0.9398)
			(stroke
				(width 0)
				(type default)
			)
			(fill no)
			(layer "B.Fab")
		)
		(pad "1" smd custom
			(at 0 -0.4445)
			(size 0.1397 0.1397)
			(layers "B.Cu" "B.Mask" "B.Paste")
			(net "MEMA_12")
			(options
				(clearance outline)
				(anchor circle)
			)
			(primitives
				(gr_poly
					(pts
						(arc
							(start -0.1778 0.2794)
							(mid -0.249642 0.249642)
							(end -0.2794 0.1778)
						)
						(arc
							(start -0.2794 -0.1778)
							(mid -0.249642 -0.249642)
							(end -0.1778 -0.2794)
						)
						(arc
							(start 0.1778 -0.2794)
							(mid 0.249642 -0.249642)
							(end 0.2794 -0.1778)
						)
						(arc
							(start 0.2794 0.1778)
							(mid 0.249642 0.249642)
							(end 0.1778 0.2794)
						)
					)
					(width 0)
					(fill yes)
				)
			)
		)
		(pad "2" smd custom
			(at 0 0.4445)
			(size 0.1397 0.1397)
			(layers "B.Cu" "B.Mask" "B.Paste")
			(net "P1V2_STBY")
			(options
				(clearance outline)
				(anchor circle)
			)
			(primitives
				(gr_poly
					(pts
						(arc
							(start -0.1778 0.2794)
							(mid -0.249642 0.249642)
							(end -0.2794 0.1778)
						)
						(arc
							(start -0.2794 -0.1778)
							(mid -0.249642 -0.249642)
							(end -0.1778 -0.2794)
						)
						(arc
							(start 0.1778 -0.2794)
							(mid 0.249642 -0.249642)
							(end 0.2794 -0.1778)
						)
						(arc
							(start 0.2794 0.1778)
							(mid 0.249642 0.249642)
							(end 0.1778 0.2794)
						)
					)
					(width 0)
					(fill yes)
				)
			)
		)
	)
	(footprint ""
		(layer "B.Cu")
		(at 165.72611 -76.267564)
		(property "Reference" "R677"
			(at 0 0 0)
			(layer "B.SilkS")
			(hide yes)
			(effects
				(font
					(size 1.27 1.27)
				)
				(justify mirror)
			)
		)
		(property "Value" "10KR2F-2-GP"
			(at -0.064008 -3.993896 0)
			(unlocked yes)
			(layer "B.Fab")
			(hide yes)
			(effects
				(font
					(size 1.016 1.016)
					(thickness 0.1524)
				)
				(justify mirror)
			)
		)
		(property "Device Type" "R402H16"
			(at -0.064008 -5.517896 0)
			(unlocked yes)
			(layer "B.Fab")
			(hide yes)
			(effects
				(font
					(size 1.016 1.016)
					(thickness 0.1524)
				)
				(justify mirror)
			)
		)
		(duplicate_pad_numbers_are_jumpers no)
		(fp_line
			(start -0.508 -0.9398)
			(end 0.508 -0.9398)
			(stroke
				(width 0.1524)
				(type default)
			)
			(layer "B.SilkS")
		)
		(fp_line
			(start 0.508 -0.9398)
			(end 0.508 0.9398)
			(stroke
				(width 0.1524)
				(type default)
			)
			(layer "B.SilkS")
		)
		(fp_rect
			(start 0.508 0.9398)
			(end -0.508 -0.9398)
			(stroke
				(width 0)
				(type default)
			)
			(fill no)
			(layer "B.CrtYd")
		)
		(fp_rect
			(start 0.508 0.9398)
			(end -0.508 -0.9398)
			(stroke
				(width 0)
				(type default)
			)
			(fill no)
			(layer "B.Fab")
		)
		(pad "1" smd custom
			(at 0 -0.4445 180)
			(size 0.1397 0.1397)
			(layers "B.Cu" "B.Mask" "B.Paste")
			(net "P1V8")
			(options
				(clearance outline)
				(anchor circle)
			)
			(primitives
				(gr_poly
					(pts
						(arc
							(start -0.1778 0.2794)
							(mid -0.249642 0.249642)
							(end -0.2794 0.1778)
						)
						(arc
							(start -0.2794 -0.1778)
							(mid -0.249642 -0.249642)
							(end -0.1778 -0.2794)
						)
						(arc
							(start 0.1778 -0.2794)
							(mid 0.249642 -0.249642)
							(end 0.2794 -0.1778)
						)
						(arc
							(start 0.2794 0.1778)
							(mid 0.249642 0.249642)
							(end 0.1778 0.2794)
						)
					)
					(width 0)
					(fill yes)
				)
			)
		)
		(pad "2" smd custom
			(at 0 0.4445 180)
			(size 0.1397 0.1397)
			(layers "B.Cu" "B.Mask" "B.Paste")
			(net "XM_WE_N")
			(options
				(clearance outline)
				(anchor circle)
			)
			(primitives
				(gr_poly
					(pts
						(arc
							(start -0.1778 0.2794)
							(mid -0.249642 0.249642)
							(end -0.2794 0.1778)
						)
						(arc
							(start -0.2794 -0.1778)
							(mid -0.249642 -0.249642)
							(end -0.1778 -0.2794)
						)
						(arc
							(start 0.1778 -0.2794)
							(mid 0.249642 -0.249642)
							(end 0.2794 -0.1778)
						)
						(arc
							(start 0.2794 0.1778)
							(mid 0.249642 0.249642)
							(end 0.1778 0.2794)
						)
					)
					(width 0)
					(fill yes)
				)
			)
		)
	)
	(footprint ""
		(layer "B.Cu")
		(at 67.973448 -148.287486 -90)
		(property "Reference" "R334"
			(at 0 0 90)
			(layer "B.SilkS")
			(hide yes)
			(effects
				(font
					(size 1.27 1.27)
				)
				(justify mirror)
			)
		)
		(property "Value" "0R2J-2-GP"
			(at -0.064008 -3.993896 270)
			(unlocked yes)
			(layer "B.Fab")
			(hide yes)
			(effects
				(font
					(size 1.016 1.016)
					(thickness 0.1524)
				)
				(justify mirror)
			)
		)
		(property "Device Type" "R402H16"
			(at -0.064008 -5.517896 270)
			(unlocked yes)
			(layer "B.Fab")
			(hide yes)
			(effects
				(font
					(size 1.016 1.016)
					(thickness 0.1524)
				)
				(justify mirror)
			)
		)
		(duplicate_pad_numbers_are_jumpers no)
		(fp_line
			(start -0.508 -0.9398)
			(end 0.508 -0.9398)
			(stroke
				(width 0.1524)
				(type default)
			)
			(layer "B.SilkS")
		)
		(fp_line
			(start 0.508 -0.9398)
			(end 0.508 0.9398)
			(stroke
				(width 0.1524)
				(type default)
			)
			(layer "B.SilkS")
		)
		(fp_rect
			(start 0.508 0.9398)
			(end -0.508 -0.9398)
			(stroke
				(width 0)
				(type default)
			)
			(fill no)
			(layer "B.CrtYd")
		)
		(fp_rect
			(start 0.508 0.9398)
			(end -0.508 -0.9398)
			(stroke
				(width 0)
				(type default)
			)
			(fill no)
			(layer "B.Fab")
		)
		(pad "1" smd custom
			(at 0 -0.4445 90)
			(size 0.1397 0.1397)
			(layers "B.Cu" "B.Mask" "B.Paste")
			(net "NCSI_TXD0")
			(options
				(clearance outline)
				(anchor circle)
			)
			(primitives
				(gr_poly
					(pts
						(arc
							(start -0.1778 0.2794)
							(mid -0.249642 0.249642)
							(end -0.2794 0.1778)
						)
						(arc
							(start -0.2794 -0.1778)
							(mid -0.249642 -0.249642)
							(end -0.1778 -0.2794)
						)
						(arc
							(start 0.1778 -0.2794)
							(mid 0.249642 -0.249642)
							(end 0.2794 -0.1778)
						)
						(arc
							(start 0.2794 0.1778)
							(mid 0.249642 0.249642)
							(end 0.1778 0.2794)
						)
					)
					(width 0)
					(fill yes)
				)
			)
		)
		(pad "2" smd custom
			(at 0 0.4445 90)
			(size 0.1397 0.1397)
			(layers "B.Cu" "B.Mask" "B.Paste")
			(net "NCSI_TXD0_R")
			(options
				(clearance outline)
				(anchor circle)
			)
			(primitives
				(gr_poly
					(pts
						(arc
							(start -0.1778 0.2794)
							(mid -0.249642 0.249642)
							(end -0.2794 0.1778)
						)
						(arc
							(start -0.2794 -0.1778)
							(mid -0.249642 -0.249642)
							(end -0.1778 -0.2794)
						)
						(arc
							(start 0.1778 -0.2794)
							(mid 0.249642 -0.249642)
							(end 0.2794 -0.1778)
						)
						(arc
							(start 0.2794 0.1778)
							(mid 0.249642 0.249642)
							(end 0.1778 0.2794)
						)
					)
					(width 0)
					(fill yes)
				)
			)
		)
	)
	(footprint ""
		(layer "B.Cu")
		(at 202.565 -57.404)
		(property "Reference" "TP117"
			(at 0 0 0)
			(layer "B.SilkS")
			(hide yes)
			(effects
				(font
					(size 1.27 1.27)
				)
				(justify mirror)
			)
		)
		(property "Value" "TPAD28-2-GP"
			(at 0.0127 -1.6637 0)
			(unlocked yes)
			(layer "B.Fab")
			(hide yes)
			(effects
				(font
					(size 1.016 1.016)
					(thickness 0.1524)
				)
				(justify mirror)
			)
		)
		(property "Device Type" "TPAD28"
			(at 0.0127 -3.1877 0)
			(unlocked yes)
			(layer "B.Fab")
			(hide yes)
			(effects
				(font
					(size 1.016 1.016)
					(thickness 0.1524)
				)
				(justify mirror)
			)
		)
		(duplicate_pad_numbers_are_jumpers no)
		(fp_poly
			(pts
				(arc
					(start 0.3556 0)
					(mid -0.3556 0)
					(end 0.3556 0)
				)
			)
			(stroke
				(width 0)
				(type default)
			)
			(fill no)
			(layer "B.CrtYd")
		)
		(fp_poly
			(pts
				(arc
					(start 0.6096 0)
					(mid -0.6096 0)
					(end 0.6096 0)
				)
			)
			(stroke
				(width 0)
				(type default)
			)
			(fill no)
			(layer "B.Fab")
		)
		(pad "1" smd circle
			(at 0 0 180)
			(size 0.7112 0.7112)
			(layers "B.Cu" "B.Mask" "B.Paste")
			(net "SIO_LOAD_0")
		)
	)
	(footprint ""
		(layer "B.Cu")
		(at 191.672718 -81.153 180)
		(property "Reference" "C300"
			(at 0 0 0)
			(layer "B.SilkS")
			(hide yes)
			(effects
				(font
					(size 1.27 1.27)
				)
				(justify mirror)
			)
		)
		(property "Value" "SCD22U10V1KX-GP"
			(at 2.8321 -1.7399 180)
			(unlocked yes)
			(layer "B.Fab")
			(hide yes)
			(effects
				(font
					(size 1.016 1.016)
					(thickness 0.1524)
				)
				(justify mirror)
			)
		)
		(property "Device Type" "C0201H13"
			(at 2.8321 -3.2639 180)
			(unlocked yes)
			(layer "B.Fab")
			(hide yes)
			(effects
				(font
					(size 1.016 1.016)
					(thickness 0.1524)
				)
				(justify mirror)
			)
		)
		(duplicate_pad_numbers_are_jumpers no)
		(fp_rect
			(start 0.2794 0.6477)
			(end -0.2794 -0.6477)
			(stroke
				(width 0)
				(type default)
			)
			(fill no)
			(layer "B.CrtYd")
		)
		(fp_rect
			(start 0.2794 0.6477)
			(end -0.2794 -0.6477)
			(stroke
				(width 0)
				(type default)
			)
			(fill no)
			(layer "B.Fab")
		)
		(pad "1" smd custom
			(at 0 -0.2794)
			(size 0.0762 0.0762)
			(layers "B.Cu" "B.Mask" "B.Paste")
			(net "PCIE_IOM_TO_COMP_13_DN_C")
			(options
				(clearance outline)
				(anchor circle)
			)
			(primitives
				(gr_poly
					(pts
						(arc
							(start 0.1524 0.127)
							(mid 0.137521 0.162921)
							(end 0.1016 0.1778)
						)
						(arc
							(start -0.1016 0.1778)
							(mid -0.137521 0.162921)
							(end -0.1524 0.127)
						)
						(arc
							(start -0.1524 -0.127)
							(mid -0.137521 -0.162921)
							(end -0.1016 -0.1778)
						)
						(arc
							(start 0.1016 -0.1778)
							(mid 0.137521 -0.162921)
							(end 0.1524 -0.127)
						)
					)
					(width 0)
					(fill yes)
				)
			)
		)
		(pad "2" smd custom
			(at 0 0.2794)
			(size 0.0762 0.0762)
			(layers "B.Cu" "B.Mask" "B.Paste")
			(net "PCIE_IOM_TO_COMP_13_DN")
			(options
				(clearance outline)
				(anchor circle)
			)
			(primitives
				(gr_poly
					(pts
						(arc
							(start 0.1524 0.127)
							(mid 0.137521 0.162921)
							(end 0.1016 0.1778)
						)
						(arc
							(start -0.1016 0.1778)
							(mid -0.137521 0.162921)
							(end -0.1524 0.127)
						)
						(arc
							(start -0.1524 -0.127)
							(mid -0.137521 -0.162921)
							(end -0.1016 -0.1778)
						)
						(arc
							(start 0.1016 -0.1778)
							(mid 0.137521 -0.162921)
							(end 0.1524 -0.127)
						)
					)
					(width 0)
					(fill yes)
				)
			)
		)
	)
)
